(kicad_pcb
	(version 20260206)
	(generator "pcbnew")
	(generator_version "10.0")
	(general
		(thickness 1.6)
		(legacy_teardrops no)
	)
	(paper "A4")
	(title_block
		(title "01162023_DA0F0TEBIF0_F0T_Expander_BD_F_brd_V02_OCP.brd")
		(comment 1 "Grand Teton / footprints 1433-1437 of 9728")
	)
	(layers
		(0 "F.Cu" signal "TOP")
		(4 "In1.Cu" signal "GND")
		(6 "In2.Cu" signal "VCC")
		(8 "In3.Cu" signal "VCC1")
		(10 "In4.Cu" signal "GND1")
		(12 "In5.Cu" signal "IN1")
		(14 "In6.Cu" signal "GND2")
		(16 "In7.Cu" signal "IN2")
		(18 "In8.Cu" signal "GND3")
		(20 "In9.Cu" signal "IN3")
		(22 "In10.Cu" signal "GND4")
		(24 "In11.Cu" signal "IN4")
		(26 "In12.Cu" signal "GND5")
		(28 "In13.Cu" signal "IN5")
		(30 "In14.Cu" signal "GND6")
		(32 "In15.Cu" signal "IN6")
		(34 "In16.Cu" signal "GND7")
		(2 "B.Cu" signal "BOTTOM")
		(9 "F.Adhes" user "F.Adhesive")
		(11 "B.Adhes" user "B.Adhesive")
		(13 "F.Paste" user "Package Geometry/Pastemask Top")
		(15 "B.Paste" user "Package Geometry/Pastemask Bottom")
		(5 "F.SilkS" user "Ref Des/Silkscreen Top")
		(7 "B.SilkS" user "Ref Des/Silkscreen Bottom")
		(1 "F.Mask" user "Board Geometry/Soldermask Top")
		(3 "B.Mask" user "Board Geometry/Soldermask Bottom")
		(17 "Dwgs.User" user "User.Drawings")
		(19 "Cmts.User" user "User.Comments")
		(21 "Eco1.User" user "User.Eco1")
		(23 "Eco2.User" user "User.Eco2")
		(25 "Edge.Cuts" user "Board Geometry/Outline")
		(27 "Margin" user)
		(31 "F.CrtYd" user "Package Geometry/Place Bound Top")
		(29 "B.CrtYd" user "Package Geometry/Place Bound Bottom")
		(35 "F.Fab" user "Ref Des/Assembly Top")
		(33 "B.Fab" user "Ref Des/Assembly Bottom")
	)
	(footprint ""
		(layer "F.Cu")
		(at 100.42906 -222.06458 90)
		(property "Reference" "PC297"
			(at 0 0 90)
			(layer "F.SilkS")
			(hide yes)
			(effects
				(font
					(size 1.27 1.27)
				)
			)
		)
		(property "Value" ""
			(at 0 0 90)
			(layer "F.Fab")
			(effects
				(font
					(size 1.27 1.27)
				)
			)
		)
		(duplicate_pad_numbers_are_jumpers no)
		(fp_line
			(start 0.7874 -0.4064)
			(end 0.7874 0.4064)
			(stroke
				(width 0.1524)
				(type default)
			)
			(layer "F.SilkS")
		)
		(fp_line
			(start -0.7874 -0.4064)
			(end 0.7874 -0.4064)
			(stroke
				(width 0.1524)
				(type default)
			)
			(layer "F.SilkS")
		)
		(fp_line
			(start 0.7874 0.4064)
			(end -0.7874 0.4064)
			(stroke
				(width 0.1524)
				(type default)
			)
			(layer "F.SilkS")
		)
		(fp_line
			(start -0.7874 0.4064)
			(end -0.7874 -0.4064)
			(stroke
				(width 0.1524)
				(type default)
			)
			(layer "F.SilkS")
		)
		(fp_line
			(start -0.12065 -0.305054)
			(end -0.12065 -0.2794)
			(stroke
				(width 0.1)
				(type default)
			)
			(layer "F.Fab")
		)
		(fp_line
			(start -0.67945 -0.305054)
			(end -0.12065 -0.305054)
			(stroke
				(width 0.1)
				(type default)
			)
			(layer "F.Fab")
		)
		(fp_line
			(start 0.67945 -0.3048)
			(end 0.67945 0.3048)
			(stroke
				(width 0.1)
				(type default)
			)
			(layer "F.Fab")
		)
		(fp_line
			(start 0.12065 -0.3048)
			(end 0.67945 -0.3048)
			(stroke
				(width 0.1)
				(type default)
			)
			(layer "F.Fab")
		)
		(fp_line
			(start 0.12065 -0.2794)
			(end 0.12065 -0.3048)
			(stroke
				(width 0.1)
				(type default)
			)
			(layer "F.Fab")
		)
		(fp_line
			(start -0.12065 -0.2794)
			(end 0.12065 -0.2794)
			(stroke
				(width 0.1)
				(type default)
			)
			(layer "F.Fab")
		)
		(fp_line
			(start 0.120396 0.2794)
			(end -0.12065 0.2794)
			(stroke
				(width 0.1)
				(type default)
			)
			(layer "F.Fab")
		)
		(fp_line
			(start -0.12065 0.2794)
			(end -0.12065 0.3048)
			(stroke
				(width 0.1)
				(type default)
			)
			(layer "F.Fab")
		)
		(fp_line
			(start 0.67945 0.3048)
			(end 0.120396 0.3048)
			(stroke
				(width 0.1)
				(type default)
			)
			(layer "F.Fab")
		)
		(fp_line
			(start 0.120396 0.3048)
			(end 0.120396 0.2794)
			(stroke
				(width 0.1)
				(type default)
			)
			(layer "F.Fab")
		)
		(fp_line
			(start -0.12065 0.3048)
			(end -0.67945 0.3048)
			(stroke
				(width 0.1)
				(type default)
			)
			(layer "F.Fab")
		)
		(fp_line
			(start -0.67945 0.3048)
			(end -0.67945 -0.305054)
			(stroke
				(width 0.1)
				(type default)
			)
			(layer "F.Fab")
		)
		(pad "1" smd circle
			(at -0.40005 0 90)
			(size 0 0)
			(layers "F.Cu" "F.Mask" "F.Paste")
			(net "P1V8_PEX_FB")
		)
		(pad "2" smd circle
			(at 0.40005 0 90)
			(size 0 0)
			(layers "F.Cu" "F.Mask" "F.Paste")
			(net "SH_P1V8_PEX_FB")
		)
	)
	(footprint ""
		(layer "F.Cu")
		(at 437.305196 -298.87291 -90)
		(property "Reference" "R3990"
			(at 0 0 270)
			(layer "F.SilkS")
			(hide yes)
			(effects
				(font
					(size 1.27 1.27)
				)
			)
		)
		(property "Value" ""
			(at 0 0 270)
			(layer "F.Fab")
			(effects
				(font
					(size 1.27 1.27)
				)
			)
		)
		(duplicate_pad_numbers_are_jumpers no)
		(fp_line
			(start -0.7874 0.4064)
			(end -0.7874 -0.4064)
			(stroke
				(width 0.1524)
				(type default)
			)
			(layer "F.SilkS")
		)
		(fp_line
			(start 0.7874 0.4064)
			(end -0.7874 0.4064)
			(stroke
				(width 0.1524)
				(type default)
			)
			(layer "F.SilkS")
		)
		(fp_line
			(start -0.7874 -0.4064)
			(end 0.7874 -0.4064)
			(stroke
				(width 0.1524)
				(type default)
			)
			(layer "F.SilkS")
		)
		(fp_line
			(start 0.7874 -0.4064)
			(end 0.7874 0.4064)
			(stroke
				(width 0.1524)
				(type default)
			)
			(layer "F.SilkS")
		)
		(fp_line
			(start -0.67945 0.3048)
			(end -0.67945 -0.305054)
			(stroke
				(width 0.1)
				(type default)
			)
			(layer "F.Fab")
		)
		(fp_line
			(start -0.12065 0.3048)
			(end -0.67945 0.3048)
			(stroke
				(width 0.1)
				(type default)
			)
			(layer "F.Fab")
		)
		(fp_line
			(start 0.120396 0.3048)
			(end 0.120396 0.2794)
			(stroke
				(width 0.1)
				(type default)
			)
			(layer "F.Fab")
		)
		(fp_line
			(start 0.67945 0.3048)
			(end 0.120396 0.3048)
			(stroke
				(width 0.1)
				(type default)
			)
			(layer "F.Fab")
		)
		(fp_line
			(start -0.12065 0.2794)
			(end -0.12065 0.3048)
			(stroke
				(width 0.1)
				(type default)
			)
			(layer "F.Fab")
		)
		(fp_line
			(start 0.120396 0.2794)
			(end -0.12065 0.2794)
			(stroke
				(width 0.1)
				(type default)
			)
			(layer "F.Fab")
		)
		(fp_line
			(start -0.12065 -0.2794)
			(end 0.12065 -0.2794)
			(stroke
				(width 0.1)
				(type default)
			)
			(layer "F.Fab")
		)
		(fp_line
			(start 0.12065 -0.2794)
			(end 0.12065 -0.3048)
			(stroke
				(width 0.1)
				(type default)
			)
			(layer "F.Fab")
		)
		(fp_line
			(start 0.12065 -0.3048)
			(end 0.67945 -0.3048)
			(stroke
				(width 0.1)
				(type default)
			)
			(layer "F.Fab")
		)
		(fp_line
			(start 0.67945 -0.3048)
			(end 0.67945 0.3048)
			(stroke
				(width 0.1)
				(type default)
			)
			(layer "F.Fab")
		)
		(fp_line
			(start -0.67945 -0.305054)
			(end -0.12065 -0.305054)
			(stroke
				(width 0.1)
				(type default)
			)
			(layer "F.Fab")
		)
		(fp_line
			(start -0.12065 -0.305054)
			(end -0.12065 -0.2794)
			(stroke
				(width 0.1)
				(type default)
			)
			(layer "F.Fab")
		)
		(pad "1" smd circle
			(at -0.40005 0 270)
			(size 0 0)
			(layers "F.Cu" "F.Mask" "F.Paste")
			(net "I2C_PEX3_HOST_SDA")
		)
		(pad "2" smd circle
			(at 0.40005 0 270)
			(size 0 0)
			(layers "F.Cu" "F.Mask" "F.Paste")
			(net "I2C_PEX3_HOST_R_SDA")
		)
	)
	(footprint ""
		(layer "F.Cu")
		(at 187.38342 -411.99181)
		(property "Reference" "R4420"
			(at 0 0 0)
			(layer "F.SilkS")
			(hide yes)
			(effects
				(font
					(size 1.27 1.27)
				)
			)
		)
		(property "Value" ""
			(at 0 0 0)
			(layer "F.Fab")
			(effects
				(font
					(size 1.27 1.27)
				)
			)
		)
		(duplicate_pad_numbers_are_jumpers no)
		(fp_line
			(start -0.7874 -0.4064)
			(end 0.7874 -0.4064)
			(stroke
				(width 0.1524)
				(type default)
			)
			(layer "F.SilkS")
		)
		(fp_line
			(start -0.7874 0.4064)
			(end -0.7874 -0.4064)
			(stroke
				(width 0.1524)
				(type default)
			)
			(layer "F.SilkS")
		)
		(fp_line
			(start 0.7874 -0.4064)
			(end 0.7874 0.4064)
			(stroke
				(width 0.1524)
				(type default)
			)
			(layer "F.SilkS")
		)
		(fp_line
			(start 0.7874 0.4064)
			(end -0.7874 0.4064)
			(stroke
				(width 0.1524)
				(type default)
			)
			(layer "F.SilkS")
		)
		(fp_line
			(start -0.67945 -0.305054)
			(end -0.12065 -0.305054)
			(stroke
				(width 0.1)
				(type default)
			)
			(layer "F.Fab")
		)
		(fp_line
			(start -0.67945 0.3048)
			(end -0.67945 -0.305054)
			(stroke
				(width 0.1)
				(type default)
			)
			(layer "F.Fab")
		)
		(fp_line
			(start -0.12065 -0.305054)
			(end -0.12065 -0.2794)
			(stroke
				(width 0.1)
				(type default)
			)
			(layer "F.Fab")
		)
		(fp_line
			(start -0.12065 -0.2794)
			(end 0.12065 -0.2794)
			(stroke
				(width 0.1)
				(type default)
			)
			(layer "F.Fab")
		)
		(fp_line
			(start -0.12065 0.2794)
			(end -0.12065 0.3048)
			(stroke
				(width 0.1)
				(type default)
			)
			(layer "F.Fab")
		)
		(fp_line
			(start -0.12065 0.3048)
			(end -0.67945 0.3048)
			(stroke
				(width 0.1)
				(type default)
			)
			(layer "F.Fab")
		)
		(fp_line
			(start 0.120396 0.2794)
			(end -0.12065 0.2794)
			(stroke
				(width 0.1)
				(type default)
			)
			(layer "F.Fab")
		)
		(fp_line
			(start 0.120396 0.3048)
			(end 0.120396 0.2794)
			(stroke
				(width 0.1)
				(type default)
			)
			(layer "F.Fab")
		)
		(fp_line
			(start 0.12065 -0.3048)
			(end 0.67945 -0.3048)
			(stroke
				(width 0.1)
				(type default)
			)
			(layer "F.Fab")
		)
		(fp_line
			(start 0.12065 -0.2794)
			(end 0.12065 -0.3048)
			(stroke
				(width 0.1)
				(type default)
			)
			(layer "F.Fab")
		)
		(fp_line
			(start 0.67945 -0.3048)
			(end 0.67945 0.3048)
			(stroke
				(width 0.1)
				(type default)
			)
			(layer "F.Fab")
		)
		(fp_line
			(start 0.67945 0.3048)
			(end 0.120396 0.3048)
			(stroke
				(width 0.1)
				(type default)
			)
			(layer "F.Fab")
		)
		(pad "1" smd circle
			(at -0.40005 0)
			(size 0 0)
			(layers "F.Cu" "F.Mask" "F.Paste")
			(net "HSC_UV_N")
		)
		(pad "2" smd circle
			(at 0.40005 0)
			(size 0 0)
			(layers "F.Cu" "F.Mask" "F.Paste")
			(net "P3V3_AUX")
		)
	)
	(footprint ""
		(layer "F.Cu")
		(at 355.854 -179.578 180)
		(property "Reference" "R4734"
			(at 0 0 180)
			(layer "F.SilkS")
			(hide yes)
			(effects
				(font
					(size 1.27 1.27)
				)
			)
		)
		(property "Value" ""
			(at 0 0 180)
			(layer "F.Fab")
			(effects
				(font
					(size 1.27 1.27)
				)
			)
		)
		(duplicate_pad_numbers_are_jumpers no)
		(fp_line
			(start 0.7874 0.4064)
			(end -0.7874 0.4064)
			(stroke
				(width 0.1524)
				(type default)
			)
			(layer "F.SilkS")
		)
		(fp_line
			(start 0.7874 -0.4064)
			(end 0.7874 0.4064)
			(stroke
				(width 0.1524)
				(type default)
			)
			(layer "F.SilkS")
		)
		(fp_line
			(start -0.7874 0.4064)
			(end -0.7874 -0.4064)
			(stroke
				(width 0.1524)
				(type default)
			)
			(layer "F.SilkS")
		)
		(fp_line
			(start -0.7874 -0.4064)
			(end 0.7874 -0.4064)
			(stroke
				(width 0.1524)
				(type default)
			)
			(layer "F.SilkS")
		)
		(fp_line
			(start 0.67945 0.3048)
			(end 0.120396 0.3048)
			(stroke
				(width 0.1)
				(type default)
			)
			(layer "F.Fab")
		)
		(fp_line
			(start 0.67945 -0.3048)
			(end 0.67945 0.3048)
			(stroke
				(width 0.1)
				(type default)
			)
			(layer "F.Fab")
		)
		(fp_line
			(start 0.12065 -0.2794)
			(end 0.12065 -0.3048)
			(stroke
				(width 0.1)
				(type default)
			)
			(layer "F.Fab")
		)
		(fp_line
			(start 0.12065 -0.3048)
			(end 0.67945 -0.3048)
			(stroke
				(width 0.1)
				(type default)
			)
			(layer "F.Fab")
		)
		(fp_line
			(start 0.120396 0.3048)
			(end 0.120396 0.2794)
			(stroke
				(width 0.1)
				(type default)
			)
			(layer "F.Fab")
		)
		(fp_line
			(start 0.120396 0.2794)
			(end -0.12065 0.2794)
			(stroke
				(width 0.1)
				(type default)
			)
			(layer "F.Fab")
		)
		(fp_line
			(start -0.12065 0.3048)
			(end -0.67945 0.3048)
			(stroke
				(width 0.1)
				(type default)
			)
			(layer "F.Fab")
		)
		(fp_line
			(start -0.12065 0.2794)
			(end -0.12065 0.3048)
			(stroke
				(width 0.1)
				(type default)
			)
			(layer "F.Fab")
		)
		(fp_line
			(start -0.12065 -0.2794)
			(end 0.12065 -0.2794)
			(stroke
				(width 0.1)
				(type default)
			)
			(layer "F.Fab")
		)
		(fp_line
			(start -0.12065 -0.305054)
			(end -0.12065 -0.2794)
			(stroke
				(width 0.1)
				(type default)
			)
			(layer "F.Fab")
		)
		(fp_line
			(start -0.67945 0.3048)
			(end -0.67945 -0.305054)
			(stroke
				(width 0.1)
				(type default)
			)
			(layer "F.Fab")
		)
		(fp_line
			(start -0.67945 -0.305054)
			(end -0.12065 -0.305054)
			(stroke
				(width 0.1)
				(type default)
			)
			(layer "F.Fab")
		)
		(pad "1" smd circle
			(at -0.40005 0 180)
			(size 0 0)
			(layers "F.Cu" "F.Mask" "F.Paste")
			(net "P3V3_AUX")
		)
		(pad "2" smd circle
			(at 0.40005 0 180)
			(size 0 0)
			(layers "F.Cu" "F.Mask" "F.Paste")
			(net "RST_PEX_NIC4_PERST_R_N")
		)
	)
	(footprint ""
		(layer "F.Cu")
		(at 95.839788 -70.52437 90)
		(property "Reference" "PC655"
			(at 0 0 90)
			(layer "F.SilkS")
			(hide yes)
			(effects
				(font
					(size 1.27 1.27)
				)
			)
		)
		(property "Value" ""
			(at 0 0 90)
			(layer "F.Fab")
			(effects
				(font
					(size 1.27 1.27)
				)
			)
		)
		(duplicate_pad_numbers_are_jumpers no)
		(fp_line
			(start 1.524 -0.762)
			(end 1.524 0.762)
			(stroke
				(width 0.1524)
				(type default)
			)
			(layer "F.SilkS")
		)
		(fp_line
			(start -1.524 -0.762)
			(end 1.524 -0.762)
			(stroke
				(width 0.1524)
				(type default)
			)
			(layer "F.SilkS")
		)
		(fp_line
			(start 1.524 0.762)
			(end -1.524 0.762)
			(stroke
				(width 0.1524)
				(type default)
			)
			(layer "F.SilkS")
		)
		(fp_line
			(start -1.524 0.762)
			(end -1.524 -0.762)
			(stroke
				(width 0.1524)
				(type default)
			)
			(layer "F.SilkS")
		)
		(fp_line
			(start 1.1049 -0.724916)
			(end -1.1049 -0.724916)
			(stroke
				(width 0.1)
				(type default)
			)
			(layer "F.Fab")
		)
		(fp_line
			(start -1.1049 -0.724916)
			(end -1.1049 0.724916)
			(stroke
				(width 0.1)
				(type default)
			)
			(layer "F.Fab")
		)
		(fp_line
			(start 1.1049 0.724916)
			(end 1.1049 -0.724916)
			(stroke
				(width 0.1)
				(type default)
			)
			(layer "F.Fab")
		)
		(fp_line
			(start -1.1049 0.724916)
			(end 1.1049 0.724916)
			(stroke
				(width 0.1)
				(type default)
			)
			(layer "F.Fab")
		)
		(pad "1" smd rect
			(at -0.889 0 270)
			(size 1.016 1.27)
			(layers "F.Cu" "F.Mask" "F.Paste")
			(net "P12V_SSD3_R")
		)
		(pad "2" smd rect
			(at 0.889 0 270)
			(size 1.016 1.27)
			(layers "F.Cu" "F.Mask" "F.Paste")
			(net "GND")
		)
	)
)
